(kicad_pcb
	(version 20260206)
	(generator "pcbnew")
	(generator_version "10.0")
	(general
		(thickness 1.6)
		(legacy_teardrops no)
	)
	(paper "A4")
	(title_block
		(title "12092022_DA0F0TFB6D0_F0T_FAN_BOARD_MP5048_D_brd_v02_OCP.brd")
		(comment 1 "Grand Teton / footprints 110-115 of 924")
	)
	(layers
		(0 "F.Cu" signal "TOP")
		(4 "In1.Cu" signal "GND")
		(6 "In2.Cu" signal "IN1")
		(8 "In3.Cu" signal "IN2")
		(10 "In4.Cu" signal "GND1")
		(2 "B.Cu" signal "BOTTOM")
		(9 "F.Adhes" user "F.Adhesive")
		(11 "B.Adhes" user "B.Adhesive")
		(13 "F.Paste" user "Package Geometry/Pastemask Top")
		(15 "B.Paste" user "Package Geometry/Pastemask Bottom")
		(5 "F.SilkS" user "Ref Des/Silkscreen Top")
		(7 "B.SilkS" user "Ref Des/Silkscreen Bottom")
		(1 "F.Mask" user "Board Geometry/Soldermask Top")
		(3 "B.Mask" user "Board Geometry/Soldermask Bottom")
		(17 "Dwgs.User" user "User.Drawings")
		(19 "Cmts.User" user "User.Comments")
		(21 "Eco1.User" user "User.Eco1")
		(23 "Eco2.User" user "User.Eco2")
		(25 "Edge.Cuts" user "Board Geometry/Outline")
		(27 "Margin" user)
		(31 "F.CrtYd" user "Package Geometry/Place Bound Top")
		(29 "B.CrtYd" user "Package Geometry/Place Bound Bottom")
		(35 "F.Fab" user "Ref Des/Assembly Top")
		(33 "B.Fab" user "Ref Des/Assembly Bottom")
	)
	(footprint ""
		(layer "F.Cu")
		(at 11.572494 -255.143 180)
		(property "Reference" "R5425"
			(at 0 0 180)
			(layer "F.SilkS")
			(hide yes)
			(effects
				(font
					(size 1.27 1.27)
				)
			)
		)
		(property "Value" ""
			(at 0 0 180)
			(layer "F.Fab")
			(effects
				(font
					(size 1.27 1.27)
				)
			)
		)
		(duplicate_pad_numbers_are_jumpers no)
		(fp_line
			(start 0.7874 0.4064)
			(end -0.7874 0.4064)
			(stroke
				(width 0.1524)
				(type default)
			)
			(layer "F.SilkS")
		)
		(fp_line
			(start 0.7874 -0.4064)
			(end 0.7874 0.4064)
			(stroke
				(width 0.1524)
				(type default)
			)
			(layer "F.SilkS")
		)
		(fp_line
			(start -0.7874 0.4064)
			(end -0.7874 -0.4064)
			(stroke
				(width 0.1524)
				(type default)
			)
			(layer "F.SilkS")
		)
		(fp_line
			(start -0.7874 -0.4064)
			(end 0.7874 -0.4064)
			(stroke
				(width 0.1524)
				(type default)
			)
			(layer "F.SilkS")
		)
		(fp_line
			(start 0.67945 0.3048)
			(end 0.120396 0.3048)
			(stroke
				(width 0.1)
				(type default)
			)
			(layer "F.Fab")
		)
		(fp_line
			(start 0.67945 -0.3048)
			(end 0.67945 0.3048)
			(stroke
				(width 0.1)
				(type default)
			)
			(layer "F.Fab")
		)
		(fp_line
			(start 0.12065 -0.2794)
			(end 0.12065 -0.3048)
			(stroke
				(width 0.1)
				(type default)
			)
			(layer "F.Fab")
		)
		(fp_line
			(start 0.12065 -0.3048)
			(end 0.67945 -0.3048)
			(stroke
				(width 0.1)
				(type default)
			)
			(layer "F.Fab")
		)
		(fp_line
			(start 0.120396 0.3048)
			(end 0.120396 0.2794)
			(stroke
				(width 0.1)
				(type default)
			)
			(layer "F.Fab")
		)
		(fp_line
			(start 0.120396 0.2794)
			(end -0.12065 0.2794)
			(stroke
				(width 0.1)
				(type default)
			)
			(layer "F.Fab")
		)
		(fp_line
			(start -0.12065 0.3048)
			(end -0.67945 0.3048)
			(stroke
				(width 0.1)
				(type default)
			)
			(layer "F.Fab")
		)
		(fp_line
			(start -0.12065 0.2794)
			(end -0.12065 0.3048)
			(stroke
				(width 0.1)
				(type default)
			)
			(layer "F.Fab")
		)
		(fp_line
			(start -0.12065 -0.2794)
			(end 0.12065 -0.2794)
			(stroke
				(width 0.1)
				(type default)
			)
			(layer "F.Fab")
		)
		(fp_line
			(start -0.12065 -0.305054)
			(end -0.12065 -0.2794)
			(stroke
				(width 0.1)
				(type default)
			)
			(layer "F.Fab")
		)
		(fp_line
			(start -0.67945 0.3048)
			(end -0.67945 -0.305054)
			(stroke
				(width 0.1)
				(type default)
			)
			(layer "F.Fab")
		)
		(fp_line
			(start -0.67945 -0.305054)
			(end -0.12065 -0.305054)
			(stroke
				(width 0.1)
				(type default)
			)
			(layer "F.Fab")
		)
		(pad "1" smd circle
			(at -0.40005 0 180)
			(size 0 0)
			(layers "F.Cu" "F.Mask" "F.Paste")
			(net "FAN_7_ON")
		)
		(pad "2" smd circle
			(at 0.40005 0 180)
			(size 0 0)
			(layers "F.Cu" "F.Mask" "F.Paste")
			(net "P52V_FAN_7_EN")
		)
	)
	(footprint ""
		(layer "F.Cu")
		(at 14.0589 -133.604 180)
		(property "Reference" "R5594"
			(at 0 0 180)
			(layer "F.SilkS")
			(hide yes)
			(effects
				(font
					(size 1.27 1.27)
				)
			)
		)
		(property "Value" ""
			(at 0 0 180)
			(layer "F.Fab")
			(effects
				(font
					(size 1.27 1.27)
				)
			)
		)
		(duplicate_pad_numbers_are_jumpers no)
		(fp_line
			(start 0.7874 0.4064)
			(end -0.7874 0.4064)
			(stroke
				(width 0.1524)
				(type default)
			)
			(layer "F.SilkS")
		)
		(fp_line
			(start 0.7874 -0.4064)
			(end 0.7874 0.4064)
			(stroke
				(width 0.1524)
				(type default)
			)
			(layer "F.SilkS")
		)
		(fp_line
			(start -0.7874 0.4064)
			(end -0.7874 -0.4064)
			(stroke
				(width 0.1524)
				(type default)
			)
			(layer "F.SilkS")
		)
		(fp_line
			(start -0.7874 -0.4064)
			(end 0.7874 -0.4064)
			(stroke
				(width 0.1524)
				(type default)
			)
			(layer "F.SilkS")
		)
		(fp_line
			(start 0.67945 0.3048)
			(end 0.120396 0.3048)
			(stroke
				(width 0.1)
				(type default)
			)
			(layer "F.Fab")
		)
		(fp_line
			(start 0.67945 -0.3048)
			(end 0.67945 0.3048)
			(stroke
				(width 0.1)
				(type default)
			)
			(layer "F.Fab")
		)
		(fp_line
			(start 0.12065 -0.2794)
			(end 0.12065 -0.3048)
			(stroke
				(width 0.1)
				(type default)
			)
			(layer "F.Fab")
		)
		(fp_line
			(start 0.12065 -0.3048)
			(end 0.67945 -0.3048)
			(stroke
				(width 0.1)
				(type default)
			)
			(layer "F.Fab")
		)
		(fp_line
			(start 0.120396 0.3048)
			(end 0.120396 0.2794)
			(stroke
				(width 0.1)
				(type default)
			)
			(layer "F.Fab")
		)
		(fp_line
			(start 0.120396 0.2794)
			(end -0.12065 0.2794)
			(stroke
				(width 0.1)
				(type default)
			)
			(layer "F.Fab")
		)
		(fp_line
			(start -0.12065 0.3048)
			(end -0.67945 0.3048)
			(stroke
				(width 0.1)
				(type default)
			)
			(layer "F.Fab")
		)
		(fp_line
			(start -0.12065 0.2794)
			(end -0.12065 0.3048)
			(stroke
				(width 0.1)
				(type default)
			)
			(layer "F.Fab")
		)
		(fp_line
			(start -0.12065 -0.2794)
			(end 0.12065 -0.2794)
			(stroke
				(width 0.1)
				(type default)
			)
			(layer "F.Fab")
		)
		(fp_line
			(start -0.12065 -0.305054)
			(end -0.12065 -0.2794)
			(stroke
				(width 0.1)
				(type default)
			)
			(layer "F.Fab")
		)
		(fp_line
			(start -0.67945 0.3048)
			(end -0.67945 -0.305054)
			(stroke
				(width 0.1)
				(type default)
			)
			(layer "F.Fab")
		)
		(fp_line
			(start -0.67945 -0.305054)
			(end -0.12065 -0.305054)
			(stroke
				(width 0.1)
				(type default)
			)
			(layer "F.Fab")
		)
		(pad "1" smd rect
			(at -0.40005 0)
			(size 0.4572 0.508)
			(layers "F.Cu" "F.Mask" "F.Paste")
			(net "FAN_6_TACH_OL")
		)
		(pad "2" smd rect
			(at 0.40005 0)
			(size 0.4572 0.508)
			(layers "F.Cu" "F.Mask" "F.Paste")
			(net "FAN_6_TACH_OL_R2")
		)
	)
	(footprint ""
		(layer "F.Cu")
		(at 37.338 -291.1856)
		(property "Reference" "R5400"
			(at 0 0 0)
			(layer "F.SilkS")
			(hide yes)
			(effects
				(font
					(size 1.27 1.27)
				)
			)
		)
		(property "Value" ""
			(at 0 0 0)
			(layer "F.Fab")
			(effects
				(font
					(size 1.27 1.27)
				)
			)
		)
		(duplicate_pad_numbers_are_jumpers no)
		(fp_line
			(start -0.7874 -0.4064)
			(end 0.7874 -0.4064)
			(stroke
				(width 0.1524)
				(type default)
			)
			(layer "F.SilkS")
		)
		(fp_line
			(start -0.7874 0.4064)
			(end -0.7874 -0.4064)
			(stroke
				(width 0.1524)
				(type default)
			)
			(layer "F.SilkS")
		)
		(fp_line
			(start 0.7874 -0.4064)
			(end 0.7874 0.4064)
			(stroke
				(width 0.1524)
				(type default)
			)
			(layer "F.SilkS")
		)
		(fp_line
			(start 0.7874 0.4064)
			(end -0.7874 0.4064)
			(stroke
				(width 0.1524)
				(type default)
			)
			(layer "F.SilkS")
		)
		(fp_line
			(start -0.67945 -0.305054)
			(end -0.12065 -0.305054)
			(stroke
				(width 0.1)
				(type default)
			)
			(layer "F.Fab")
		)
		(fp_line
			(start -0.67945 0.3048)
			(end -0.67945 -0.305054)
			(stroke
				(width 0.1)
				(type default)
			)
			(layer "F.Fab")
		)
		(fp_line
			(start -0.12065 -0.305054)
			(end -0.12065 -0.2794)
			(stroke
				(width 0.1)
				(type default)
			)
			(layer "F.Fab")
		)
		(fp_line
			(start -0.12065 -0.2794)
			(end 0.12065 -0.2794)
			(stroke
				(width 0.1)
				(type default)
			)
			(layer "F.Fab")
		)
		(fp_line
			(start -0.12065 0.2794)
			(end -0.12065 0.3048)
			(stroke
				(width 0.1)
				(type default)
			)
			(layer "F.Fab")
		)
		(fp_line
			(start -0.12065 0.3048)
			(end -0.67945 0.3048)
			(stroke
				(width 0.1)
				(type default)
			)
			(layer "F.Fab")
		)
		(fp_line
			(start 0.120396 0.2794)
			(end -0.12065 0.2794)
			(stroke
				(width 0.1)
				(type default)
			)
			(layer "F.Fab")
		)
		(fp_line
			(start 0.120396 0.3048)
			(end 0.120396 0.2794)
			(stroke
				(width 0.1)
				(type default)
			)
			(layer "F.Fab")
		)
		(fp_line
			(start 0.12065 -0.3048)
			(end 0.67945 -0.3048)
			(stroke
				(width 0.1)
				(type default)
			)
			(layer "F.Fab")
		)
		(fp_line
			(start 0.12065 -0.2794)
			(end 0.12065 -0.3048)
			(stroke
				(width 0.1)
				(type default)
			)
			(layer "F.Fab")
		)
		(fp_line
			(start 0.67945 -0.3048)
			(end 0.67945 0.3048)
			(stroke
				(width 0.1)
				(type default)
			)
			(layer "F.Fab")
		)
		(fp_line
			(start 0.67945 0.3048)
			(end 0.120396 0.3048)
			(stroke
				(width 0.1)
				(type default)
			)
			(layer "F.Fab")
		)
		(pad "1" smd rect
			(at -0.40005 0 180)
			(size 0.4572 0.508)
			(layers "F.Cu" "F.Mask" "F.Paste")
			(net "FAN_0_OK_LED_R_N")
		)
		(pad "2" smd rect
			(at 0.40005 0 180)
			(size 0.4572 0.508)
			(layers "F.Cu" "F.Mask" "F.Paste")
			(net "FAN_0_OK_R_LED_N")
		)
	)
	(footprint ""
		(layer "F.Cu")
		(at 5.715 -65.278 -90)
		(property "Reference" "PR48"
			(at 0 0 270)
			(layer "F.SilkS")
			(hide yes)
			(effects
				(font
					(size 1.27 1.27)
				)
			)
		)
		(property "Value" ""
			(at 0 0 270)
			(layer "F.Fab")
			(effects
				(font
					(size 1.27 1.27)
				)
			)
		)
		(duplicate_pad_numbers_are_jumpers no)
		(fp_line
			(start -0.7874 0.4064)
			(end -0.7874 -0.4064)
			(stroke
				(width 0.1524)
				(type default)
			)
			(layer "F.SilkS")
		)
		(fp_line
			(start 0.7874 0.4064)
			(end -0.7874 0.4064)
			(stroke
				(width 0.1524)
				(type default)
			)
			(layer "F.SilkS")
		)
		(fp_line
			(start -0.7874 -0.4064)
			(end 0.7874 -0.4064)
			(stroke
				(width 0.1524)
				(type default)
			)
			(layer "F.SilkS")
		)
		(fp_line
			(start 0.7874 -0.4064)
			(end 0.7874 0.4064)
			(stroke
				(width 0.1524)
				(type default)
			)
			(layer "F.SilkS")
		)
		(fp_line
			(start -0.67945 0.3048)
			(end -0.67945 -0.305054)
			(stroke
				(width 0.1)
				(type default)
			)
			(layer "F.Fab")
		)
		(fp_line
			(start -0.12065 0.3048)
			(end -0.67945 0.3048)
			(stroke
				(width 0.1)
				(type default)
			)
			(layer "F.Fab")
		)
		(fp_line
			(start 0.120396 0.3048)
			(end 0.120396 0.2794)
			(stroke
				(width 0.1)
				(type default)
			)
			(layer "F.Fab")
		)
		(fp_line
			(start 0.67945 0.3048)
			(end 0.120396 0.3048)
			(stroke
				(width 0.1)
				(type default)
			)
			(layer "F.Fab")
		)
		(fp_line
			(start -0.12065 0.2794)
			(end -0.12065 0.3048)
			(stroke
				(width 0.1)
				(type default)
			)
			(layer "F.Fab")
		)
		(fp_line
			(start 0.120396 0.2794)
			(end -0.12065 0.2794)
			(stroke
				(width 0.1)
				(type default)
			)
			(layer "F.Fab")
		)
		(fp_line
			(start -0.12065 -0.2794)
			(end 0.12065 -0.2794)
			(stroke
				(width 0.1)
				(type default)
			)
			(layer "F.Fab")
		)
		(fp_line
			(start 0.12065 -0.2794)
			(end 0.12065 -0.3048)
			(stroke
				(width 0.1)
				(type default)
			)
			(layer "F.Fab")
		)
		(fp_line
			(start 0.12065 -0.3048)
			(end 0.67945 -0.3048)
			(stroke
				(width 0.1)
				(type default)
			)
			(layer "F.Fab")
		)
		(fp_line
			(start 0.67945 -0.3048)
			(end 0.67945 0.3048)
			(stroke
				(width 0.1)
				(type default)
			)
			(layer "F.Fab")
		)
		(fp_line
			(start -0.67945 -0.305054)
			(end -0.12065 -0.305054)
			(stroke
				(width 0.1)
				(type default)
			)
			(layer "F.Fab")
		)
		(fp_line
			(start -0.12065 -0.305054)
			(end -0.12065 -0.2794)
			(stroke
				(width 0.1)
				(type default)
			)
			(layer "F.Fab")
		)
		(pad "1" smd rect
			(at -0.40005 0 90)
			(size 0.4572 0.508)
			(layers "F.Cu" "F.Mask" "F.Paste")
			(net "FAN_4_FAULT_R")
		)
		(pad "2" smd rect
			(at 0.40005 0 90)
			(size 0.4572 0.508)
			(layers "F.Cu" "F.Mask" "F.Paste")
			(net "FAN_4_FAULT")
		)
	)
	(footprint ""
		(layer "F.Cu")
		(at 19.939 -154.94 -90)
		(property "Reference" "C1933"
			(at 0 0 270)
			(layer "F.SilkS")
			(hide yes)
			(effects
				(font
					(size 1.27 1.27)
				)
			)
		)
		(property "Value" ""
			(at 0 0 270)
			(layer "F.Fab")
			(effects
				(font
					(size 1.27 1.27)
				)
			)
		)
		(duplicate_pad_numbers_are_jumpers no)
		(fp_line
			(start -0.7874 0.4064)
			(end -0.7874 -0.4064)
			(stroke
				(width 0.1524)
				(type default)
			)
			(layer "F.SilkS")
		)
		(fp_line
			(start 0.7874 0.4064)
			(end -0.7874 0.4064)
			(stroke
				(width 0.1524)
				(type default)
			)
			(layer "F.SilkS")
		)
		(fp_line
			(start -0.7874 -0.4064)
			(end 0.7874 -0.4064)
			(stroke
				(width 0.1524)
				(type default)
			)
			(layer "F.SilkS")
		)
		(fp_line
			(start 0.7874 -0.4064)
			(end 0.7874 0.4064)
			(stroke
				(width 0.1524)
				(type default)
			)
			(layer "F.SilkS")
		)
		(fp_line
			(start -0.67945 0.3048)
			(end -0.67945 -0.305054)
			(stroke
				(width 0.1)
				(type default)
			)
			(layer "F.Fab")
		)
		(fp_line
			(start -0.12065 0.3048)
			(end -0.67945 0.3048)
			(stroke
				(width 0.1)
				(type default)
			)
			(layer "F.Fab")
		)
		(fp_line
			(start 0.120396 0.3048)
			(end 0.120396 0.2794)
			(stroke
				(width 0.1)
				(type default)
			)
			(layer "F.Fab")
		)
		(fp_line
			(start 0.67945 0.3048)
			(end 0.120396 0.3048)
			(stroke
				(width 0.1)
				(type default)
			)
			(layer "F.Fab")
		)
		(fp_line
			(start -0.12065 0.2794)
			(end -0.12065 0.3048)
			(stroke
				(width 0.1)
				(type default)
			)
			(layer "F.Fab")
		)
		(fp_line
			(start 0.120396 0.2794)
			(end -0.12065 0.2794)
			(stroke
				(width 0.1)
				(type default)
			)
			(layer "F.Fab")
		)
		(fp_line
			(start -0.12065 -0.2794)
			(end 0.12065 -0.2794)
			(stroke
				(width 0.1)
				(type default)
			)
			(layer "F.Fab")
		)
		(fp_line
			(start 0.12065 -0.2794)
			(end 0.12065 -0.3048)
			(stroke
				(width 0.1)
				(type default)
			)
			(layer "F.Fab")
		)
		(fp_line
			(start 0.12065 -0.3048)
			(end 0.67945 -0.3048)
			(stroke
				(width 0.1)
				(type default)
			)
			(layer "F.Fab")
		)
		(fp_line
			(start 0.67945 -0.3048)
			(end 0.67945 0.3048)
			(stroke
				(width 0.1)
				(type default)
			)
			(layer "F.Fab")
		)
		(fp_line
			(start -0.67945 -0.305054)
			(end -0.12065 -0.305054)
			(stroke
				(width 0.1)
				(type default)
			)
			(layer "F.Fab")
		)
		(fp_line
			(start -0.12065 -0.305054)
			(end -0.12065 -0.2794)
			(stroke
				(width 0.1)
				(type default)
			)
			(layer "F.Fab")
		)
		(pad "1" smd circle
			(at -0.40005 0 270)
			(size 0 0)
			(layers "F.Cu" "F.Mask" "F.Paste")
			(net "GND")
		)
		(pad "2" smd circle
			(at 0.40005 0 270)
			(size 0 0)
			(layers "F.Cu" "F.Mask" "F.Paste")
			(net "P3V3_AUX")
		)
	)
	(footprint ""
		(layer "F.Cu")
		(at 46.99 -221.234 90)
		(property "Reference" "C2121"
			(at 0 0 90)
			(layer "F.SilkS")
			(hide yes)
			(effects
				(font
					(size 1.27 1.27)
				)
			)
		)
		(property "Value" ""
			(at 0 0 90)
			(layer "F.Fab")
			(effects
				(font
					(size 1.27 1.27)
				)
			)
		)
		(duplicate_pad_numbers_are_jumpers no)
		(fp_line
			(start 1.2954 -0.5842)
			(end 1.2954 0.5842)
			(stroke
				(width 0.1524)
				(type default)
			)
			(layer "F.SilkS")
		)
		(fp_line
			(start -1.2954 -0.5842)
			(end 1.2954 -0.5842)
			(stroke
				(width 0.1524)
				(type default)
			)
			(layer "F.SilkS")
		)
		(fp_line
			(start 1.2954 0.5842)
			(end -1.2954 0.5842)
			(stroke
				(width 0.1524)
				(type default)
			)
			(layer "F.SilkS")
		)
		(fp_line
			(start -1.2954 0.5842)
			(end -1.2954 -0.5842)
			(stroke
				(width 0.1524)
				(type default)
			)
			(layer "F.SilkS")
		)
		(fp_line
			(start 0.8636 -0.4572)
			(end 0.8636 -0.4064)
			(stroke
				(width 0.1)
				(type default)
			)
			(layer "F.Fab")
		)
		(fp_line
			(start -0.8636 -0.4572)
			(end 0.8636 -0.4572)
			(stroke
				(width 0.1)
				(type default)
			)
			(layer "F.Fab")
		)
		(fp_line
			(start 1.1938 -0.4064)
			(end 1.1938 0.4064)
			(stroke
				(width 0.1)
				(type default)
			)
			(layer "F.Fab")
		)
		(fp_line
			(start 0.8636 -0.4064)
			(end 1.1938 -0.4064)
			(stroke
				(width 0.1)
				(type default)
			)
			(layer "F.Fab")
		)
		(fp_line
			(start -0.8636 -0.4064)
			(end -0.8636 -0.4572)
			(stroke
				(width 0.1)
				(type default)
			)
			(layer "F.Fab")
		)
		(fp_line
			(start -1.1938 -0.4064)
			(end -0.8636 -0.4064)
			(stroke
				(width 0.1)
				(type default)
			)
			(layer "F.Fab")
		)
		(fp_line
			(start 1.1938 0.4064)
			(end 0.8636 0.4064)
			(stroke
				(width 0.1)
				(type default)
			)
			(layer "F.Fab")
		)
		(fp_line
			(start 0.8636 0.4064)
			(end 0.8636 0.4572)
			(stroke
				(width 0.1)
				(type default)
			)
			(layer "F.Fab")
		)
		(fp_line
			(start -0.8636 0.4064)
			(end -1.1938 0.4064)
			(stroke
				(width 0.1)
				(type default)
			)
			(layer "F.Fab")
		)
		(fp_line
			(start -1.1938 0.4064)
			(end -1.1938 -0.4064)
			(stroke
				(width 0.1)
				(type default)
			)
			(layer "F.Fab")
		)
		(fp_line
			(start 0.8636 0.4572)
			(end -0.8636 0.4572)
			(stroke
				(width 0.1)
				(type default)
			)
			(layer "F.Fab")
		)
		(fp_line
			(start -0.8636 0.4572)
			(end -0.8636 0.4064)
			(stroke
				(width 0.1)
				(type default)
			)
			(layer "F.Fab")
		)
		(pad "1" smd rect
			(at -0.7366 0)
			(size 0.7112 0.8128)
			(layers "F.Cu" "F.Mask" "F.Paste")
			(net "U406_D1")
		)
		(pad "2" smd rect
			(at 0.7366 0)
			(size 0.7112 0.8128)
			(layers "F.Cu" "F.Mask" "F.Paste")
			(net "GND")
		)
	)
)
